# S9S_MB_2U (Grand Teton) — schematic netlist excerpt (pin names and nets, part order shuffled) for the footprints in the layout excerpt that follows; sources: Cadence DE-HDL packaged netlist, KiCad conversion of 03242023_DA0F0TMBIJ0_F0T_Motherboard_J_brd_V01_OCP.brd

C931  Q_CAP_DIFFBUS  DIFF BUS_0.22UF 6.3V 20% X6S  pkg C0201  page 173 : \1\ = P5E_CPU0_PE0_TX_C_DP<1> ; \2\ = P5E_CPU0_PE0_TX_DP<1>
C2381  Q_CAP  100NF 50V 10% EMPTY  pkg C0402  page 307 : A = P12V_AUX_UV_ADR_TRIGGER ; B = GND
R3240  Q_RES  2.2K 5% EMPTY  pkg 0402LF  page 241 : A = SMB_OCP_SFF_3V3AUX_SCL ; B = P3V3_AUX

(kicad_pcb
	(version 20260206)
	(generator "pcbnew")
	(generator_version "10.0")
	(general
		(thickness 1.6)
		(legacy_teardrops no)
	)
	(paper "A4")
	(title_block
		(title "03242023_DA0F0TMBIJ0_F0T_Motherboard_J_brd_V01_OCP.brd")
		(comment 1 "Grand Teton / footprints 5-7 of 6105")
	)
	(layers
		(0 "F.Cu" signal "TOP")
		(4 "In1.Cu" signal "GND")
		(6 "In2.Cu" signal "IN1")
		(8 "In3.Cu" signal "GND1")
		(10 "In4.Cu" signal "IN2")
		(12 "In5.Cu" signal "GND2")
		(14 "In6.Cu" signal "IN3")
		(16 "In7.Cu" signal "GND3")
		(18 "In8.Cu" signal "VCC")
		(20 "In9.Cu" signal "VCC1")
		(22 "In10.Cu" signal "GND4")
		(24 "In11.Cu" signal "IN4")
		(26 "In12.Cu" signal "GND5")
		(28 "In13.Cu" signal "IN5")
		(30 "In14.Cu" signal "GND6")
		(32 "In15.Cu" signal "IN6")
		(34 "In16.Cu" signal "GND7")
		(2 "B.Cu" signal "BOTTOM")
		(9 "F.Adhes" user "F.Adhesive")
		(11 "B.Adhes" user "B.Adhesive")
		(13 "F.Paste" user "Package Geometry/Pastemask Top")
		(15 "B.Paste" user "Package Geometry/Pastemask Bottom")
		(5 "F.SilkS" user "Ref Des/Silkscreen Top")
		(7 "B.SilkS" user "Ref Des/Silkscreen Bottom")
		(1 "F.Mask" user "Board Geometry/Soldermask Top")
		(3 "B.Mask" user "Board Geometry/Soldermask Bottom")
		(17 "Dwgs.User" user "User.Drawings")
		(19 "Cmts.User" user "User.Comments")
		(21 "Eco1.User" user "User.Eco1")
		(23 "Eco2.User" user "User.Eco2")
		(25 "Edge.Cuts" user "Board Geometry/Outline")
		(27 "Margin" user)
		(31 "F.CrtYd" user "Package Geometry/Place Bound Top")
		(29 "B.CrtYd" user "Package Geometry/Place Bound Bottom")
		(35 "F.Fab" user "Ref Des/Assembly Top")
		(33 "B.Fab" user "Ref Des/Assembly Bottom")
	)
	(footprint ""
		(layer "F.Cu")
		(at 438.87771 -44.976288 180)
		(property "Reference" "R3240"
			(at 0 0 180)
			(layer "F.SilkS")
			(hide yes)
			(effects
				(font
					(size 1.27 1.27)
				)
			)
		)
		(property "Value" ""
			(at 0 0 180)
			(layer "F.Fab")
			(effects
				(font
					(size 1.27 1.27)
				)
			)
		)
		(duplicate_pad_numbers_are_jumpers no)
		(fp_line
			(start 0.7874 0.4064)
			(end -0.7874 0.4064)
			(stroke
				(width 0.1524)
				(type default)
			)
			(layer "F.SilkS")
		)
		(fp_line
			(start 0.7874 -0.4064)
			(end 0.7874 0.4064)
			(stroke
				(width 0.1524)
				(type default)
			)
			(layer "F.SilkS")
		)
		(fp_line
			(start -0.7874 0.4064)
			(end -0.7874 -0.4064)
			(stroke
				(width 0.1524)
				(type default)
			)
			(layer "F.SilkS")
		)
		(fp_line
			(start -0.7874 -0.4064)
			(end 0.7874 -0.4064)
			(stroke
				(width 0.1524)
				(type default)
			)
			(layer "F.SilkS")
		)
		(fp_line
			(start 0.67945 0.3048)
			(end 0.120396 0.3048)
			(stroke
				(width 0.1)
				(type default)
			)
			(layer "F.Fab")
		)
		(fp_line
			(start 0.67945 -0.3048)
			(end 0.67945 0.3048)
			(stroke
				(width 0.1)
				(type default)
			)
			(layer "F.Fab")
		)
		(fp_line
			(start 0.12065 -0.2794)
			(end 0.12065 -0.3048)
			(stroke
				(width 0.1)
				(type default)
			)
			(layer "F.Fab")
		)
		(fp_line
			(start 0.12065 -0.3048)
			(end 0.67945 -0.3048)
			(stroke
				(width 0.1)
				(type default)
			)
			(layer "F.Fab")
		)
		(fp_line
			(start 0.120396 0.3048)
			(end 0.120396 0.2794)
			(stroke
				(width 0.1)
				(type default)
			)
			(layer "F.Fab")
		)
		(fp_line
			(start 0.120396 0.2794)
			(end -0.12065 0.2794)
			(stroke
				(width 0.1)
				(type default)
			)
			(layer "F.Fab")
		)
		(fp_line
			(start -0.12065 0.3048)
			(end -0.67945 0.3048)
			(stroke
				(width 0.1)
				(type default)
			)
			(layer "F.Fab")
		)
		(fp_line
			(start -0.12065 0.2794)
			(end -0.12065 0.3048)
			(stroke
				(width 0.1)
				(type default)
			)
			(layer "F.Fab")
		)
		(fp_line
			(start -0.12065 -0.2794)
			(end 0.12065 -0.2794)
			(stroke
				(width 0.1)
				(type default)
			)
			(layer "F.Fab")
		)
		(fp_line
			(start -0.12065 -0.305054)
			(end -0.12065 -0.2794)
			(stroke
				(width 0.1)
				(type default)
			)
			(layer "F.Fab")
		)
		(fp_line
			(start -0.67945 0.3048)
			(end -0.67945 -0.305054)
			(stroke
				(width 0.1)
				(type default)
			)
			(layer "F.Fab")
		)
		(fp_line
			(start -0.67945 -0.305054)
			(end -0.12065 -0.305054)
			(stroke
				(width 0.1)
				(type default)
			)
			(layer "F.Fab")
		)
		(pad "1" smd circle
			(at -0.40005 0 180)
			(size 0 0)
			(layers "F.Cu" "F.Mask" "F.Paste")
			(net "SMB_OCP_SFF_3V3AUX_SCL")
		)
		(pad "2" smd circle
			(at 0.40005 0 180)
			(size 0 0)
			(layers "F.Cu" "F.Mask" "F.Paste")
			(net "P3V3_AUX")
		)
	)
	(footprint ""
		(layer "F.Cu")
		(at 349.100648 -408.517344 -90)
		(property "Reference" "C931"
			(at 0 0 270)
			(layer "F.SilkS")
			(hide yes)
			(effects
				(font
					(size 1.27 1.27)
				)
			)
		)
		(property "Value" ""
			(at 0 0 270)
			(layer "F.Fab")
			(effects
				(font
					(size 1.27 1.27)
				)
			)
		)
		(duplicate_pad_numbers_are_jumpers no)
		(fp_line
			(start -0.299974 0.150114)
			(end -0.299974 -0.150114)
			(stroke
				(width 0.1)
				(type default)
			)
			(layer "F.Fab")
		)
		(fp_line
			(start 0.299974 0.150114)
			(end -0.299974 0.150114)
			(stroke
				(width 0.1)
				(type default)
			)
			(layer "F.Fab")
		)
		(fp_line
			(start -0.299974 -0.150114)
			(end 0.299974 -0.150114)
			(stroke
				(width 0.1)
				(type default)
			)
			(layer "F.Fab")
		)
		(fp_line
			(start 0.299974 -0.150114)
			(end 0.299974 0.150114)
			(stroke
				(width 0.1)
				(type default)
			)
			(layer "F.Fab")
		)
		(pad "1" smd rect
			(at -0.2667 0 270)
			(size 0.3048 0.381)
			(layers "F.Cu" "F.Mask" "F.Paste")
			(net "P5E_CPU0_PE0_TX_C_DP<1>")
		)
		(pad "2" smd rect
			(at 0.2667 0 270)
			(size 0.3048 0.381)
			(layers "F.Cu" "F.Mask" "F.Paste")
			(net "P5E_CPU0_PE0_TX_DP<1>")
		)
	)
	(footprint ""
		(layer "F.Cu")
		(at 203.7588 -92.6338 -90)
		(property "Reference" "C2381"
			(at 0 0 270)
			(layer "F.SilkS")
			(hide yes)
			(effects
				(font
					(size 1.27 1.27)
				)
			)
		)
		(property "Value" ""
			(at 0 0 270)
			(layer "F.Fab")
			(effects
				(font
					(size 1.27 1.27)
				)
			)
		)
		(duplicate_pad_numbers_are_jumpers no)
		(fp_line
			(start -0.7874 0.4064)
			(end -0.7874 -0.4064)
			(stroke
				(width 0.1524)
				(type default)
			)
			(layer "F.SilkS")
		)
		(fp_line
			(start 0.7874 0.4064)
			(end -0.7874 0.4064)
			(stroke
				(width 0.1524)
				(type default)
			)
			(layer "F.SilkS")
		)
		(fp_line
			(start -0.7874 -0.4064)
			(end 0.7874 -0.4064)
			(stroke
				(width 0.1524)
				(type default)
			)
			(layer "F.SilkS")
		)
		(fp_line
			(start 0.7874 -0.4064)
			(end 0.7874 0.4064)
			(stroke
				(width 0.1524)
				(type default)
			)
			(layer "F.SilkS")
		)
		(fp_line
			(start -0.67945 0.3048)
			(end -0.67945 -0.305054)
			(stroke
				(width 0.1)
				(type default)
			)
			(layer "F.Fab")
		)
		(fp_line
			(start -0.12065 0.3048)
			(end -0.67945 0.3048)
			(stroke
				(width 0.1)
				(type default)
			)
			(layer "F.Fab")
		)
		(fp_line
			(start 0.120396 0.3048)
			(end 0.120396 0.2794)
			(stroke
				(width 0.1)
				(type default)
			)
			(layer "F.Fab")
		)
		(fp_line
			(start 0.67945 0.3048)
			(end 0.120396 0.3048)
			(stroke
				(width 0.1)
				(type default)
			)
			(layer "F.Fab")
		)
		(fp_line
			(start -0.12065 0.2794)
			(end -0.12065 0.3048)
			(stroke
				(width 0.1)
				(type default)
			)
			(layer "F.Fab")
		)
		(fp_line
			(start 0.120396 0.2794)
			(end -0.12065 0.2794)
			(stroke
				(width 0.1)
				(type default)
			)
			(layer "F.Fab")
		)
		(fp_line
			(start -0.12065 -0.2794)
			(end 0.12065 -0.2794)
			(stroke
				(width 0.1)
				(type default)
			)
			(layer "F.Fab")
		)
		(fp_line
			(start 0.12065 -0.2794)
			(end 0.12065 -0.3048)
			(stroke
				(width 0.1)
				(type default)
			)
			(layer "F.Fab")
		)
		(fp_line
			(start 0.12065 -0.3048)
			(end 0.67945 -0.3048)
			(stroke
				(width 0.1)
				(type default)
			)
			(layer "F.Fab")
		)
		(fp_line
			(start 0.67945 -0.3048)
			(end 0.67945 0.3048)
			(stroke
				(width 0.1)
				(type default)
			)
			(layer "F.Fab")
		)
		(fp_line
			(start -0.67945 -0.305054)
			(end -0.12065 -0.305054)
			(stroke
				(width 0.1)
				(type default)
			)
			(layer "F.Fab")
		)
		(fp_line
			(start -0.12065 -0.305054)
			(end -0.12065 -0.2794)
			(stroke
				(width 0.1)
				(type default)
			)
			(layer "F.Fab")
		)
		(pad "1" smd circle
			(at -0.40005 0 270)
			(size 0 0)
			(layers "F.Cu" "F.Mask" "F.Paste")
			(net "P12V_AUX_UV_ADR_TRIGGER")
		)
		(pad "2" smd circle
			(at 0.40005 0 270)
			(size 0 0)
			(layers "F.Cu" "F.Mask" "F.Paste")
			(net "GND")
		)
	)
)
